# Stackup_grand teton_MB_18L_2p413mm_EM-890K_VL411_Rev0p6_20230202.xls — Information (pcb-stackup)
| Stackup Information : |  |  |  |  |  |  |  |  |  |
| Stackup Type |  |  | Single Material |  |  |  |  |  |  |
| Project Name |  |  | F0T |  |  |  |  |  |  |
| Board Class |  |  | Motherboard |  |  |  |  |  |  |
| Number of Layers |  |  | 18 |  |  |  |  |  |  |
| PCB Material |  |  | EM-890K |  |  |  |  |  |  |
| Copper Foil |  |  | VL411 (Roughness < 1um) |  |  |  |  |  |  |
| PCB Thickness (mm) |  |  | 2.413 |  |  |  |  |  |  |
| PCB Thickness (mil) |  |  | 95 |  |  |  |  |  |  |
| Aspect Ratio |  |  | 9.69 |  |  |  |  |  |  |
| Last Update |  |  | 44959 |  |  |  |  |  |  |
| Revision |  |  | 0.6 |  |  |  |  |  |  |
| Creator |  |  | Allen |  |  |  |  |  |  |
| Loss Requirement Table : |  |  |  |  |  |  |  |  |  |
| SDD21 @ Freq(GHz) |  | 4 | 4 | 4 | 4 | 4 | 4 | 4 | 4 |
| Requirement (db/inch) | Layer | TOP | IN1 | IN2 | IN3 | IN4 | IN5 | IN6 | BOTTOM |
|  | Loss | 0.58 | 0.35 | 0.35 | 0.35 | 0.35 | 0.35 | 0.35 | 0.58 |
| SDD21 @ Freq(GHz) |  | 8 | 8 | 8 | 8 | 8 | 8 | 8 | 8 |
| Requirement (db/inch) | Layer | TOP | IN1 | IN2 | IN3 | IN4 | IN5 | IN6 | BOTTOM |
|  | Loss | 1.05 | 0.5 | 0.5 | 0.5 | 0.5 | 0.5 | 0.5 | 1.05 |
| SDD21 @ Freq(GHz) |  | 16 | 16 | 16 | 16 | 16 | 16 | 16 | 16 |
| Requirement (db/inch) | Layer | TOP | IN1 | IN2 | IN3 | IN4 | IN5 | IN6 | BOTTOM |
|  | Loss | 1.78 | 0.72 | 0.72 | 0.72 | 0.72 | 0.72 | 0.72 | 1.78 |
| Stackup History : |  |  |  |  |  |  |  |  |  |
| Date (yyyy/mm/dd) | Revision | Notes |  |  |  |  |  |  |  |
| 44510 | 0.1 | Follow "Stackup_S9S_Main_Board_E1S _14L_2mm_EM-890K_HVLP3_Rev0p4_20210206.xls" |  |  |  |  |  |  |  |
| 44515 | 0.2 | Change PP type from 1078x2 to 1080x2 |  |  |  |  |  |  |  |
| 44651 | 0.3 | Modify 16GHz inner loss spec from 0.85 dB/inch to 0.72 dB/inch |  |  |  |  |  |  |  |
| 44757 | 0.4 | Add VIPPO processing based on Meta request, please refer to Mail "Re_ _External_  FW_ Meta_Quanta via half-plugging discussion.msg" |  |  |  |  |  |  |  |
| 44942 | 0.5 | Control neck mode 3.5/4/3.5 mils to 93 ohm, pin pitch W+S+W =11 mils |  |  |  |  |  |  |  |
| 44959 | 0.6 | Change 93 ohm neck mode impedancec control from 3.5/4/3.5 to 4/3/4 mils, pin pitch W+S+W =11 mils |  |  |  |  |  |  |  |
